(kicad_pcb
	(version 20260206)
	(generator "pcbnew")
	(generator_version "10.0")
	(general
		(thickness 1.6)
		(legacy_teardrops no)
	)
	(paper "A4")
	(title_block
		(title "netronome-mezz — pcbd0082-001_rev01_jul9_a.brd")
		(comment 1 "Open CloudServer (Microsoft) / footprints 670-677 of 714")
	)
	(layers
		(0 "F.Cu" signal "TOP")
		(4 "In1.Cu" signal "02_GND")
		(6 "In2.Cu" signal "03_SIG")
		(8 "In3.Cu" signal "04_SIG")
		(10 "In4.Cu" signal "05_GND")
		(12 "In5.Cu" signal "06_PWR1")
		(14 "In6.Cu" signal "07_SIG")
		(16 "In7.Cu" signal "08_SIG")
		(18 "In8.Cu" signal "09_GND")
		(2 "B.Cu" signal "BOTTOM")
		(9 "F.Adhes" user "F.Adhesive")
		(11 "B.Adhes" user "B.Adhesive")
		(13 "F.Paste" user "Package Geometry/Pastemask Top")
		(15 "B.Paste" user "Package Geometry/Pastemask Bottom")
		(5 "F.SilkS" user "Ref Des/Silkscreen Top")
		(7 "B.SilkS" user "Ref Des/Silkscreen Bottom")
		(1 "F.Mask" user "Board Geometry/Soldermask Top")
		(3 "B.Mask" user "Board Geometry/Soldermask Bottom")
		(17 "Dwgs.User" user "User.Drawings")
		(19 "Cmts.User" user "User.Comments")
		(21 "Eco1.User" user "User.Eco1")
		(23 "Eco2.User" user "User.Eco2")
		(25 "Edge.Cuts" user "Board Geometry/Outline")
		(27 "Margin" user)
		(31 "F.CrtYd" user "Package Geometry/Place Bound Top")
		(29 "B.CrtYd" user "Package Geometry/Place Bound Bottom")
		(35 "F.Fab" user "Ref Des/Assembly Top")
		(33 "B.Fab" user "Ref Des/Assembly Bottom")
		(45 "User.4" user "COMPVAL_TYPE_BOTTOM")
	)
	(footprint ""
		(layer "B.Cu")
		(at 60.736988 13.042011 -90)
		(property "Reference" "C186"
			(at 0 0 90)
			(layer "B.SilkS")
			(hide yes)
			(effects
				(font
					(size 1.27 1.27)
				)
				(justify mirror)
			)
		)
		(property "Value" ""
			(at 0 0 90)
			(layer "B.Fab")
			(effects
				(font
					(size 1.27 1.27)
				)
				(justify mirror)
			)
		)
		(duplicate_pad_numbers_are_jumpers no)
		(fp_circle
			(center 0 0)
			(end 0 -0.104648)
			(stroke
				(width 0.1016)
				(type default)
			)
			(fill no)
			(layer "B.SilkS")
		)
		(fp_poly
			(pts
				(xy 0.381 -0.889) (xy 0.381 0.889) (xy -0.381 0.889) (xy -0.381 -0.889)
			)
			(stroke
				(width 0)
				(type default)
			)
			(fill no)
			(layer "B.CrtYd")
		)
		(fp_line
			(start -0.508 1.016)
			(end 0.508 1.016)
			(stroke
				(width 0.0254)
				(type default)
			)
			(layer "B.Fab")
		)
		(fp_line
			(start 0.508 1.016)
			(end 0.508 -1.016)
			(stroke
				(width 0.0254)
				(type default)
			)
			(layer "B.Fab")
		)
		(fp_line
			(start -0.508 -1.016)
			(end -0.508 1.016)
			(stroke
				(width 0.0254)
				(type default)
			)
			(layer "B.Fab")
		)
		(fp_line
			(start 0.254 -1.016)
			(end -0.508 -1.016)
			(stroke
				(width 0.0254)
				(type default)
			)
			(layer "B.Fab")
		)
		(fp_line
			(start 0.508 -1.016)
			(end 0.254 -1.016)
			(stroke
				(width 0.0254)
				(type default)
			)
			(layer "B.Fab")
		)
		(pad "1" smd custom
			(at 0 -0.500126 90)
			(size 0.127 0.127)
			(layers "B.Cu" "B.Mask" "B.Paste")
			(net "VDDA_DDR0_32A")
			(options
				(clearance outline)
				(anchor circle)
			)
			(primitives
				(gr_poly
					(pts
						(xy -0.1778 0.254) (xy 0.1778 0.254) (xy 0.254 0.1778) (xy 0.254 -0.1778) (xy 0.1778 -0.254) (xy -0.1778 -0.254)
						(xy -0.254 -0.1778) (xy -0.254 0.1778)
					)
					(width 0)
					(fill yes)
				)
			)
		)
		(pad "2" smd custom
			(at 0 0.500126 90)
			(size 0.127 0.127)
			(layers "B.Cu" "B.Mask" "B.Paste")
			(net "GND")
			(options
				(clearance outline)
				(anchor circle)
			)
			(primitives
				(gr_poly
					(pts
						(xy -0.1778 0.254) (xy 0.1778 0.254) (xy 0.254 0.1778) (xy 0.254 -0.1778) (xy 0.1778 -0.254) (xy -0.1778 -0.254)
						(xy -0.254 -0.1778) (xy -0.254 0.1778)
					)
					(width 0)
					(fill yes)
				)
			)
		)
	)
	(footprint ""
		(layer "B.Cu")
		(at 78.74 43.688)
		(property "Reference" "C136"
			(at 0.22733 4.445 270)
			(unlocked yes)
			(layer "B.SilkS")
			(effects
				(font
					(size 0.7874 0.5842)
					(thickness 0.127)
				)
				(justify left mirror)
			)
		)
		(property "Value" "10UF"
			(at 0.148158 1.7526 270)
			(unlocked yes)
			(layer "B.Fab")
			(hide yes)
			(effects
				(font
					(size 1.27 0.9652)
					(thickness 0.000001)
				)
				(justify left mirror)
			)
		)
		(property "Device Type" "CAPC0058"
			(at 0.148158 1.7526 270)
			(unlocked yes)
			(layer "B.Fab")
			(hide yes)
			(effects
				(font
					(size 1.27 0.9652)
					(thickness 0.000001)
				)
				(justify left mirror)
			)
		)
		(duplicate_pad_numbers_are_jumpers no)
		(fp_circle
			(center 0 0)
			(end 0.127 0)
			(stroke
				(width 0.2032)
				(type default)
			)
			(fill no)
			(layer "B.SilkS")
		)
		(fp_poly
			(pts
				(xy -0.7874 -1.6637) (xy 0.7874 -1.6637) (xy 0.7874 1.6637) (xy -0.7874 1.6637)
			)
			(stroke
				(width 0)
				(type default)
			)
			(fill no)
			(layer "B.CrtYd")
		)
		(fp_line
			(start -0.4064 -0.7874)
			(end -0.4064 0.8128)
			(stroke
				(width 0.0254)
				(type default)
			)
			(layer "B.Fab")
		)
		(fp_line
			(start -0.4064 0.8128)
			(end 0.4064 0.8128)
			(stroke
				(width 0.0254)
				(type default)
			)
			(layer "B.Fab")
		)
		(fp_line
			(start 0.4064 -0.7874)
			(end -0.4064 -0.7874)
			(stroke
				(width 0.0254)
				(type default)
			)
			(layer "B.Fab")
		)
		(fp_line
			(start 0.4064 0.8128)
			(end 0.4064 -0.7874)
			(stroke
				(width 0.0254)
				(type default)
			)
			(layer "B.Fab")
		)
		(pad "1" smd rect
			(at 0 -0.8001 180)
			(size 0.8636 0.9652)
			(layers "B.Cu" "B.Mask" "B.Paste")
			(net "DDR_VTT")
		)
		(pad "2" smd rect
			(at 0 0.8001 180)
			(size 0.8636 0.9652)
			(layers "B.Cu" "B.Mask" "B.Paste")
			(net "GND")
		)
		(zone
			(layer "B.Cu")
			(hatch none 0.5)
			(connect_pads
				(clearance 0)
			)
			(min_thickness 0.25)
			(keepout
				(tracks not_allowed)
				(vias allowed)
				(pads allowed)
				(copperpour not_allowed)
				(footprints allowed)
			)
			(placement
				(enabled no)
				(sheetname "")
			)
			(fill
				(thermal_gap 0.5)
				(thermal_bridge_width 0.5)
				(island_removal_mode 0)
			)
			(polygon
				(pts
					(xy 78.8035 43.434) (xy 78.6765 43.434) (xy 78.6765 43.942) (xy 78.8035 43.942)
				)
			)
		)
	)
	(footprint ""
		(layer "B.Cu")
		(at 53.237003 11.542014)
		(property "Reference" "C28"
			(at 0.076327 2.300986 270)
			(unlocked yes)
			(layer "B.SilkS")
			(effects
				(font
					(size 0.7874 0.5842)
					(thickness 0.127)
				)
				(justify mirror)
			)
		)
		(property "Value" ""
			(at 0 0 0)
			(layer "B.Fab")
			(effects
				(font
					(size 1.27 1.27)
				)
				(justify mirror)
			)
		)
		(duplicate_pad_numbers_are_jumpers no)
		(fp_circle
			(center 0 0)
			(end 0.104648 0)
			(stroke
				(width 0.1016)
				(type default)
			)
			(fill no)
			(layer "B.SilkS")
		)
		(fp_poly
			(pts
				(xy 0.381 -0.889) (xy 0.381 0.889) (xy -0.381 0.889) (xy -0.381 -0.889)
			)
			(stroke
				(width 0)
				(type default)
			)
			(fill no)
			(layer "B.CrtYd")
		)
		(fp_line
			(start -0.508 -1.016)
			(end -0.508 1.016)
			(stroke
				(width 0.0254)
				(type default)
			)
			(layer "B.Fab")
		)
		(fp_line
			(start -0.508 1.016)
			(end 0.508 1.016)
			(stroke
				(width 0.0254)
				(type default)
			)
			(layer "B.Fab")
		)
		(fp_line
			(start 0.254 -1.016)
			(end -0.508 -1.016)
			(stroke
				(width 0.0254)
				(type default)
			)
			(layer "B.Fab")
		)
		(fp_line
			(start 0.508 -1.016)
			(end 0.254 -1.016)
			(stroke
				(width 0.0254)
				(type default)
			)
			(layer "B.Fab")
		)
		(fp_line
			(start 0.508 1.016)
			(end 0.508 -1.016)
			(stroke
				(width 0.0254)
				(type default)
			)
			(layer "B.Fab")
		)
		(pad "1" smd custom
			(at 0 -0.500126 180)
			(size 0.127 0.127)
			(layers "B.Cu" "B.Mask" "B.Paste")
			(net "VDDA_PLL")
			(options
				(clearance outline)
				(anchor circle)
			)
			(primitives
				(gr_poly
					(pts
						(xy -0.1778 0.254) (xy 0.1778 0.254) (xy 0.254 0.1778) (xy 0.254 -0.1778) (xy 0.1778 -0.254) (xy -0.1778 -0.254)
						(xy -0.254 -0.1778) (xy -0.254 0.1778)
					)
					(width 0)
					(fill yes)
				)
			)
		)
		(pad "2" smd custom
			(at 0 0.500126 180)
			(size 0.127 0.127)
			(layers "B.Cu" "B.Mask" "B.Paste")
			(net "GND")
			(options
				(clearance outline)
				(anchor circle)
			)
			(primitives
				(gr_poly
					(pts
						(xy -0.1778 0.254) (xy 0.1778 0.254) (xy 0.254 0.1778) (xy 0.254 -0.1778) (xy 0.1778 -0.254) (xy -0.1778 -0.254)
						(xy -0.254 -0.1778) (xy -0.254 0.1778)
					)
					(width 0)
					(fill yes)
				)
			)
		)
	)
	(footprint ""
		(layer "B.Cu")
		(at 77.051002 30.612994)
		(property "Reference" "V_A-CB3"
			(at 0 0 0)
			(layer "B.SilkS")
			(hide yes)
			(effects
				(font
					(size 1.27 1.27)
				)
				(justify mirror)
			)
		)
		(property "Value" ""
			(at 0 0 0)
			(layer "B.Fab")
			(effects
				(font
					(size 1.27 1.27)
				)
				(justify mirror)
			)
		)
		(duplicate_pad_numbers_are_jumpers no)
		(pad "1" thru_hole circle
			(at 0 0 180)
			(size 0.4572 0.4572)
			(drill 0.20574)
			(layers "*.Cu" "*.Mask")
			(remove_unused_layers no)
			(net "DDR0_32A_CB3")
			(clearance 0.1143)
			(thermal_gap 0.1143)
		)
	)
	(footprint ""
		(layer "B.Cu")
		(at 47.237015 10.542016)
		(property "Reference" "C92"
			(at 0 0 0)
			(layer "B.SilkS")
			(hide yes)
			(effects
				(font
					(size 1.27 1.27)
				)
				(justify mirror)
			)
		)
		(property "Value" ""
			(at 0 0 0)
			(layer "B.Fab")
			(effects
				(font
					(size 1.27 1.27)
				)
				(justify mirror)
			)
		)
		(duplicate_pad_numbers_are_jumpers no)
		(fp_circle
			(center 0 0)
			(end 0.104648 0)
			(stroke
				(width 0.1016)
				(type default)
			)
			(fill no)
			(layer "B.SilkS")
		)
		(fp_poly
			(pts
				(xy 0.381 -0.889) (xy 0.381 0.889) (xy -0.381 0.889) (xy -0.381 -0.889)
			)
			(stroke
				(width 0)
				(type default)
			)
			(fill no)
			(layer "B.CrtYd")
		)
		(fp_line
			(start -0.508 -1.016)
			(end -0.508 1.016)
			(stroke
				(width 0.0254)
				(type default)
			)
			(layer "B.Fab")
		)
		(fp_line
			(start -0.508 1.016)
			(end 0.508 1.016)
			(stroke
				(width 0.0254)
				(type default)
			)
			(layer "B.Fab")
		)
		(fp_line
			(start 0.254 -1.016)
			(end -0.508 -1.016)
			(stroke
				(width 0.0254)
				(type default)
			)
			(layer "B.Fab")
		)
		(fp_line
			(start 0.508 -1.016)
			(end 0.254 -1.016)
			(stroke
				(width 0.0254)
				(type default)
			)
			(layer "B.Fab")
		)
		(fp_line
			(start 0.508 1.016)
			(end 0.508 -1.016)
			(stroke
				(width 0.0254)
				(type default)
			)
			(layer "B.Fab")
		)
		(pad "1" smd custom
			(at 0 -0.500126 180)
			(size 0.127 0.127)
			(layers "B.Cu" "B.Mask" "B.Paste")
			(net "VDDA_SERDES")
			(options
				(clearance outline)
				(anchor circle)
			)
			(primitives
				(gr_poly
					(pts
						(xy -0.1778 0.254) (xy 0.1778 0.254) (xy 0.254 0.1778) (xy 0.254 -0.1778) (xy 0.1778 -0.254) (xy -0.1778 -0.254)
						(xy -0.254 -0.1778) (xy -0.254 0.1778)
					)
					(width 0)
					(fill yes)
				)
			)
		)
		(pad "2" smd custom
			(at 0 0.500126 180)
			(size 0.127 0.127)
			(layers "B.Cu" "B.Mask" "B.Paste")
			(net "GND")
			(options
				(clearance outline)
				(anchor circle)
			)
			(primitives
				(gr_poly
					(pts
						(xy -0.1778 0.254) (xy 0.1778 0.254) (xy 0.254 0.1778) (xy 0.254 -0.1778) (xy 0.1778 -0.254) (xy -0.1778 -0.254)
						(xy -0.254 -0.1778) (xy -0.254 0.1778)
					)
					(width 0)
					(fill yes)
				)
			)
		)
	)
	(footprint ""
		(layer "B.Cu")
		(at 62.736984 13.042011 -90)
		(property "Reference" "R188"
			(at 0 0 90)
			(layer "B.SilkS")
			(hide yes)
			(effects
				(font
					(size 1.27 1.27)
				)
				(justify mirror)
			)
		)
		(property "Value" ""
			(at 0 0 90)
			(layer "B.Fab")
			(effects
				(font
					(size 1.27 1.27)
				)
				(justify mirror)
			)
		)
		(duplicate_pad_numbers_are_jumpers no)
		(fp_circle
			(center 0 0)
			(end 0 -0.104648)
			(stroke
				(width 0.1016)
				(type default)
			)
			(fill no)
			(layer "B.SilkS")
		)
		(fp_poly
			(pts
				(xy 0.381 -0.889) (xy 0.381 0.889) (xy -0.381 0.889) (xy -0.381 -0.889)
			)
			(stroke
				(width 0)
				(type default)
			)
			(fill no)
			(layer "B.CrtYd")
		)
		(fp_line
			(start -0.508 1.016)
			(end 0.508 1.016)
			(stroke
				(width 0.0254)
				(type default)
			)
			(layer "B.Fab")
		)
		(fp_line
			(start 0.508 1.016)
			(end 0.508 -1.016)
			(stroke
				(width 0.0254)
				(type default)
			)
			(layer "B.Fab")
		)
		(fp_line
			(start -0.508 -1.016)
			(end -0.508 1.016)
			(stroke
				(width 0.0254)
				(type default)
			)
			(layer "B.Fab")
		)
		(fp_line
			(start 0.254 -1.016)
			(end -0.508 -1.016)
			(stroke
				(width 0.0254)
				(type default)
			)
			(layer "B.Fab")
		)
		(fp_line
			(start 0.508 -1.016)
			(end 0.254 -1.016)
			(stroke
				(width 0.0254)
				(type default)
			)
			(layer "B.Fab")
		)
		(pad "1" smd custom
			(at 0 -0.500126 90)
			(size 0.127 0.127)
			(layers "B.Cu" "B.Mask" "B.Paste")
			(net "GND")
			(options
				(clearance outline)
				(anchor circle)
			)
			(primitives
				(gr_poly
					(pts
						(xy -0.1778 0.254) (xy 0.1778 0.254) (xy 0.254 0.1778) (xy 0.254 -0.1778) (xy 0.1778 -0.254) (xy -0.1778 -0.254)
						(xy -0.254 -0.1778) (xy -0.254 0.1778)
					)
					(width 0)
					(fill yes)
				)
			)
		)
		(pad "2" smd custom
			(at 0 0.500126 90)
			(size 0.127 0.127)
			(layers "B.Cu" "B.Mask" "B.Paste")
			(net "A_AZQ")
			(options
				(clearance outline)
				(anchor circle)
			)
			(primitives
				(gr_poly
					(pts
						(xy -0.1778 0.254) (xy 0.1778 0.254) (xy 0.254 0.1778) (xy 0.254 -0.1778) (xy 0.1778 -0.254) (xy -0.1778 -0.254)
						(xy -0.254 -0.1778) (xy -0.254 0.1778)
					)
					(width 0)
					(fill yes)
				)
			)
		)
	)
	(footprint ""
		(layer "B.Cu")
		(at 29.21 32.639)
		(property "Reference" "R172"
			(at -0.02667 5.08 270)
			(unlocked yes)
			(layer "B.SilkS")
			(effects
				(font
					(size 0.7874 0.5842)
					(thickness 0.127)
				)
				(justify left mirror)
			)
		)
		(property "Value" "0"
			(at 0.148158 1.3462 270)
			(unlocked yes)
			(layer "B.Fab")
			(hide yes)
			(effects
				(font
					(size 1.27 0.9652)
					(thickness 0.000001)
				)
				(justify left mirror)
			)
		)
		(property "Device Type" "REST1111"
			(at 0.148158 1.3462 270)
			(unlocked yes)
			(layer "B.Fab")
			(hide yes)
			(effects
				(font
					(size 1.27 0.9652)
					(thickness 0.000001)
				)
				(justify left mirror)
			)
		)
		(duplicate_pad_numbers_are_jumpers no)
		(fp_poly
			(pts
				(xy -0.635 1.0668) (xy -0.635 -1.0668) (xy 0.635 -1.0668) (xy 0.635 1.0668)
			)
			(stroke
				(width 0)
				(type default)
			)
			(fill no)
			(layer "B.CrtYd")
		)
		(fp_line
			(start -0.254 -0.508)
			(end -0.254 0.508)
			(stroke
				(width 0.0254)
				(type default)
			)
			(layer "B.Fab")
		)
		(fp_line
			(start -0.254 0.508)
			(end 0.254 0.508)
			(stroke
				(width 0.0254)
				(type default)
			)
			(layer "B.Fab")
		)
		(fp_line
			(start 0.254 -0.508)
			(end -0.254 -0.508)
			(stroke
				(width 0.0254)
				(type default)
			)
			(layer "B.Fab")
		)
		(fp_line
			(start 0.254 0.508)
			(end 0.254 -0.508)
			(stroke
				(width 0.0254)
				(type default)
			)
			(layer "B.Fab")
		)
		(pad "1" smd rect
			(at 0 -0.4191 180)
			(size 0.508 0.5334)
			(layers "B.Cu" "B.Mask" "B.Paste")
			(net "NFP_CORE_VID2")
		)
		(pad "2" smd rect
			(at 0 0.4191 180)
			(size 0.508 0.5334)
			(layers "B.Cu" "B.Mask" "B.Paste")
			(net "_NFP_CORE_VID2")
		)
		(zone
			(layer "B.Cu")
			(hatch none 0.5)
			(connect_pads
				(clearance 0)
			)
			(min_thickness 0.25)
			(keepout
				(tracks not_allowed)
				(vias allowed)
				(pads allowed)
				(copperpour not_allowed)
				(footprints allowed)
			)
			(placement
				(enabled no)
				(sheetname "")
			)
			(fill
				(thermal_gap 0.5)
				(thermal_bridge_width 0.5)
				(island_removal_mode 0)
			)
			(polygon
				(pts
					(xy 29.1846 32.6136) (xy 29.1846 32.6644) (xy 29.2354 32.6644) (xy 29.2354 32.6136)
				)
			)
		)
	)
	(footprint ""
		(layer "B.Cu")
		(at 65.786 35.6362 180)
		(property "Reference" "C201"
			(at 0 0 0)
			(layer "B.SilkS")
			(hide yes)
			(effects
				(font
					(size 1.27 1.27)
				)
				(justify mirror)
			)
		)
		(property "Value" "1UF"
			(at 0.091846 0.2921 90)
			(unlocked yes)
			(layer "B.Fab")
			(hide yes)
			(effects
				(font
					(size 0.7874 0.5842)
					(thickness 0.2032)
				)
				(justify left mirror)
			)
		)
		(property "Device Type" "CAPC0028"
			(at 0.091846 0.2921 90)
			(unlocked yes)
			(layer "B.Fab")
			(hide yes)
			(effects
				(font
					(size 0.7874 0.5842)
					(thickness 0.2032)
				)
				(justify left mirror)
			)
		)
		(duplicate_pad_numbers_are_jumpers no)
		(fp_poly
			(pts
				(xy -0.635 1.0668) (xy -0.635 -1.0668) (xy 0.635 -1.0668) (xy 0.635 1.0668)
			)
			(stroke
				(width 0)
				(type default)
			)
			(fill no)
			(layer "B.CrtYd")
		)
		(fp_line
			(start 0.254 0.508)
			(end 0.254 -0.508)
			(stroke
				(width 0.0254)
				(type default)
			)
			(layer "B.Fab")
		)
		(fp_line
			(start 0.254 -0.508)
			(end -0.254 -0.508)
			(stroke
				(width 0.0254)
				(type default)
			)
			(layer "B.Fab")
		)
		(fp_line
			(start -0.254 0.508)
			(end 0.254 0.508)
			(stroke
				(width 0.0254)
				(type default)
			)
			(layer "B.Fab")
		)
		(fp_line
			(start -0.254 -0.508)
			(end -0.254 0.508)
			(stroke
				(width 0.0254)
				(type default)
			)
			(layer "B.Fab")
		)
		(pad "1" smd rect
			(at 0 -0.4191)
			(size 0.508 0.5334)
			(layers "B.Cu" "B.Mask" "B.Paste")
			(net "VDD_5.0V")
		)
		(pad "2" smd rect
			(at 0 0.4191)
			(size 0.508 0.5334)
			(layers "B.Cu" "B.Mask" "B.Paste")
			(net "GND")
		)
		(zone
			(layer "B.Cu")
			(hatch none 0.5)
			(connect_pads
				(clearance 0)
			)
			(min_thickness 0.25)
			(keepout
				(tracks not_allowed)
				(vias allowed)
				(pads allowed)
				(copperpour not_allowed)
				(footprints allowed)
			)
			(placement
				(enabled no)
				(sheetname "")
			)
			(fill
				(thermal_gap 0.5)
				(thermal_bridge_width 0.5)
				(island_removal_mode 0)
			)
			(polygon
				(pts
					(xy 65.8114 35.6616) (xy 65.8114 35.6108) (xy 65.7606 35.6108) (xy 65.7606 35.6616)
				)
			)
		)
	)
)
